(kicad_pcb
	(version 20260206)
	(generator "pcbnew")
	(generator_version "10.0")
	(general
		(thickness 1.6)
		(legacy_teardrops no)
	)
	(paper "A4")
	(title_block
		(title "01162023_DA0F0TEBIF0_F0T_Expander_BD_F_brd_V02_OCP.brd")
		(comment 1 "Grand Teton / footprints 7499-7506 of 9728")
	)
	(layers
		(0 "F.Cu" signal "TOP")
		(4 "In1.Cu" signal "GND")
		(6 "In2.Cu" signal "VCC")
		(8 "In3.Cu" signal "VCC1")
		(10 "In4.Cu" signal "GND1")
		(12 "In5.Cu" signal "IN1")
		(14 "In6.Cu" signal "GND2")
		(16 "In7.Cu" signal "IN2")
		(18 "In8.Cu" signal "GND3")
		(20 "In9.Cu" signal "IN3")
		(22 "In10.Cu" signal "GND4")
		(24 "In11.Cu" signal "IN4")
		(26 "In12.Cu" signal "GND5")
		(28 "In13.Cu" signal "IN5")
		(30 "In14.Cu" signal "GND6")
		(32 "In15.Cu" signal "IN6")
		(34 "In16.Cu" signal "GND7")
		(2 "B.Cu" signal "BOTTOM")
		(9 "F.Adhes" user "F.Adhesive")
		(11 "B.Adhes" user "B.Adhesive")
		(13 "F.Paste" user "Package Geometry/Pastemask Top")
		(15 "B.Paste" user "Package Geometry/Pastemask Bottom")
		(5 "F.SilkS" user "Ref Des/Silkscreen Top")
		(7 "B.SilkS" user "Ref Des/Silkscreen Bottom")
		(1 "F.Mask" user "Board Geometry/Soldermask Top")
		(3 "B.Mask" user "Board Geometry/Soldermask Bottom")
		(17 "Dwgs.User" user "User.Drawings")
		(19 "Cmts.User" user "User.Comments")
		(21 "Eco1.User" user "User.Eco1")
		(23 "Eco2.User" user "User.Eco2")
		(25 "Edge.Cuts" user "Board Geometry/Outline")
		(27 "Margin" user)
		(31 "F.CrtYd" user "Package Geometry/Place Bound Top")
		(29 "B.CrtYd" user "Package Geometry/Place Bound Bottom")
		(35 "F.Fab" user "Ref Des/Assembly Top")
		(33 "B.Fab" user "Ref Des/Assembly Bottom")
	)
	(footprint ""
		(layer "B.Cu")
		(at 343.027 -233.553 90)
		(property "Reference" "R3556"
			(at 0 0 90)
			(layer "B.SilkS")
			(hide yes)
			(effects
				(font
					(size 1.27 1.27)
				)
				(justify mirror)
			)
		)
		(property "Value" ""
			(at 0 0 90)
			(layer "B.Fab")
			(effects
				(font
					(size 1.27 1.27)
				)
				(justify mirror)
			)
		)
		(duplicate_pad_numbers_are_jumpers no)
		(fp_line
			(start 0.7874 -0.4064)
			(end -0.7874 -0.4064)
			(stroke
				(width 0.1524)
				(type default)
			)
			(layer "B.SilkS")
		)
		(fp_line
			(start -0.7874 -0.4064)
			(end -0.7874 0.4064)
			(stroke
				(width 0.1524)
				(type default)
			)
			(layer "B.SilkS")
		)
		(fp_line
			(start 0.7874 0.4064)
			(end 0.7874 -0.4064)
			(stroke
				(width 0.1524)
				(type default)
			)
			(layer "B.SilkS")
		)
		(fp_line
			(start -0.7874 0.4064)
			(end 0.7874 0.4064)
			(stroke
				(width 0.1524)
				(type default)
			)
			(layer "B.SilkS")
		)
		(fp_line
			(start 0.67945 -0.305054)
			(end 0.12065 -0.305054)
			(stroke
				(width 0.1)
				(type default)
			)
			(layer "B.Fab")
		)
		(fp_line
			(start 0.12065 -0.305054)
			(end 0.12065 -0.2794)
			(stroke
				(width 0.1)
				(type default)
			)
			(layer "B.Fab")
		)
		(fp_line
			(start -0.12065 -0.3048)
			(end -0.67945 -0.3048)
			(stroke
				(width 0.1)
				(type default)
			)
			(layer "B.Fab")
		)
		(fp_line
			(start -0.67945 -0.3048)
			(end -0.67945 0.3048)
			(stroke
				(width 0.1)
				(type default)
			)
			(layer "B.Fab")
		)
		(fp_line
			(start 0.12065 -0.2794)
			(end -0.12065 -0.2794)
			(stroke
				(width 0.1)
				(type default)
			)
			(layer "B.Fab")
		)
		(fp_line
			(start -0.12065 -0.2794)
			(end -0.12065 -0.3048)
			(stroke
				(width 0.1)
				(type default)
			)
			(layer "B.Fab")
		)
		(fp_line
			(start 0.12065 0.2794)
			(end 0.12065 0.3048)
			(stroke
				(width 0.1)
				(type default)
			)
			(layer "B.Fab")
		)
		(fp_line
			(start -0.120396 0.2794)
			(end 0.12065 0.2794)
			(stroke
				(width 0.1)
				(type default)
			)
			(layer "B.Fab")
		)
		(fp_line
			(start 0.67945 0.3048)
			(end 0.67945 -0.305054)
			(stroke
				(width 0.1)
				(type default)
			)
			(layer "B.Fab")
		)
		(fp_line
			(start 0.12065 0.3048)
			(end 0.67945 0.3048)
			(stroke
				(width 0.1)
				(type default)
			)
			(layer "B.Fab")
		)
		(fp_line
			(start -0.120396 0.3048)
			(end -0.120396 0.2794)
			(stroke
				(width 0.1)
				(type default)
			)
			(layer "B.Fab")
		)
		(fp_line
			(start -0.67945 0.3048)
			(end -0.120396 0.3048)
			(stroke
				(width 0.1)
				(type default)
			)
			(layer "B.Fab")
		)
		(pad "1" smd circle
			(at 0.40005 0 270)
			(size 0 0)
			(layers "B.Cu" "B.Mask" "B.Paste")
			(net "SSD4_CLK_EN_R_N")
		)
		(pad "2" smd circle
			(at -0.40005 0 270)
			(size 0 0)
			(layers "B.Cu" "B.Mask" "B.Paste")
			(net "SSD4_CLK_EN_N")
		)
	)
	(footprint ""
		(layer "B.Cu")
		(at 379.857 -245.872 180)
		(property "Reference" "R943"
			(at 0 0 0)
			(layer "B.SilkS")
			(hide yes)
			(effects
				(font
					(size 1.27 1.27)
				)
				(justify mirror)
			)
		)
		(property "Value" ""
			(at 0 0 0)
			(layer "B.Fab")
			(effects
				(font
					(size 1.27 1.27)
				)
				(justify mirror)
			)
		)
		(duplicate_pad_numbers_are_jumpers no)
		(fp_line
			(start 0.7874 0.4064)
			(end 0.7874 -0.4064)
			(stroke
				(width 0.1524)
				(type default)
			)
			(layer "B.SilkS")
		)
		(fp_line
			(start 0.7874 -0.4064)
			(end -0.7874 -0.4064)
			(stroke
				(width 0.1524)
				(type default)
			)
			(layer "B.SilkS")
		)
		(fp_line
			(start -0.7874 0.4064)
			(end 0.7874 0.4064)
			(stroke
				(width 0.1524)
				(type default)
			)
			(layer "B.SilkS")
		)
		(fp_line
			(start -0.7874 -0.4064)
			(end -0.7874 0.4064)
			(stroke
				(width 0.1524)
				(type default)
			)
			(layer "B.SilkS")
		)
		(fp_line
			(start 0.67945 0.3048)
			(end 0.67945 -0.305054)
			(stroke
				(width 0.1)
				(type default)
			)
			(layer "B.Fab")
		)
		(fp_line
			(start 0.67945 -0.305054)
			(end 0.12065 -0.305054)
			(stroke
				(width 0.1)
				(type default)
			)
			(layer "B.Fab")
		)
		(fp_line
			(start 0.12065 0.3048)
			(end 0.67945 0.3048)
			(stroke
				(width 0.1)
				(type default)
			)
			(layer "B.Fab")
		)
		(fp_line
			(start 0.12065 0.2794)
			(end 0.12065 0.3048)
			(stroke
				(width 0.1)
				(type default)
			)
			(layer "B.Fab")
		)
		(fp_line
			(start 0.12065 -0.2794)
			(end -0.12065 -0.2794)
			(stroke
				(width 0.1)
				(type default)
			)
			(layer "B.Fab")
		)
		(fp_line
			(start 0.12065 -0.305054)
			(end 0.12065 -0.2794)
			(stroke
				(width 0.1)
				(type default)
			)
			(layer "B.Fab")
		)
		(fp_line
			(start -0.120396 0.3048)
			(end -0.120396 0.2794)
			(stroke
				(width 0.1)
				(type default)
			)
			(layer "B.Fab")
		)
		(fp_line
			(start -0.120396 0.2794)
			(end 0.12065 0.2794)
			(stroke
				(width 0.1)
				(type default)
			)
			(layer "B.Fab")
		)
		(fp_line
			(start -0.12065 -0.2794)
			(end -0.12065 -0.3048)
			(stroke
				(width 0.1)
				(type default)
			)
			(layer "B.Fab")
		)
		(fp_line
			(start -0.12065 -0.3048)
			(end -0.67945 -0.3048)
			(stroke
				(width 0.1)
				(type default)
			)
			(layer "B.Fab")
		)
		(fp_line
			(start -0.67945 0.3048)
			(end -0.120396 0.3048)
			(stroke
				(width 0.1)
				(type default)
			)
			(layer "B.Fab")
		)
		(fp_line
			(start -0.67945 -0.3048)
			(end -0.67945 0.3048)
			(stroke
				(width 0.1)
				(type default)
			)
			(layer "B.Fab")
		)
		(pad "1" smd circle
			(at 0.40005 0)
			(size 0 0)
			(layers "B.Cu" "B.Mask" "B.Paste")
			(net "UART_PEX2_SDB_BUF_TX")
		)
		(pad "2" smd circle
			(at -0.40005 0)
			(size 0 0)
			(layers "B.Cu" "B.Mask" "B.Paste")
			(net "P3V3_AUX")
		)
	)
	(footprint ""
		(layer "B.Cu")
		(at 394.65504 -300.1772)
		(property "Reference" "C3547"
			(at 0 0 0)
			(layer "B.SilkS")
			(hide yes)
			(effects
				(font
					(size 1.27 1.27)
				)
				(justify mirror)
			)
		)
		(property "Value" ""
			(at 0 0 0)
			(layer "B.Fab")
			(effects
				(font
					(size 1.27 1.27)
				)
				(justify mirror)
			)
		)
		(duplicate_pad_numbers_are_jumpers no)
		(fp_line
			(start -0.299974 -0.150114)
			(end -0.299974 0.150114)
			(stroke
				(width 0.1)
				(type default)
			)
			(layer "B.Fab")
		)
		(fp_line
			(start -0.299974 0.150114)
			(end 0.299974 0.150114)
			(stroke
				(width 0.1)
				(type default)
			)
			(layer "B.Fab")
		)
		(fp_line
			(start 0.299974 -0.150114)
			(end -0.299974 -0.150114)
			(stroke
				(width 0.1)
				(type default)
			)
			(layer "B.Fab")
		)
		(fp_line
			(start 0.299974 0.150114)
			(end 0.299974 -0.150114)
			(stroke
				(width 0.1)
				(type default)
			)
			(layer "B.Fab")
		)
		(pad "1" smd rect
			(at 0.2667 0 180)
			(size 0.3048 0.381)
			(layers "B.Cu" "B.Mask" "B.Paste")
			(net "PCEPLL1_VDDA18_PEX3")
		)
		(pad "2" smd rect
			(at -0.2667 0 180)
			(size 0.3048 0.381)
			(layers "B.Cu" "B.Mask" "B.Paste")
			(net "GND")
		)
	)
	(footprint ""
		(layer "B.Cu")
		(at 288.99993 -288.299906 90)
		(property "Reference" "C3291"
			(at 0 0 90)
			(layer "B.SilkS")
			(hide yes)
			(effects
				(font
					(size 1.27 1.27)
				)
				(justify mirror)
			)
		)
		(property "Value" ""
			(at 0 0 90)
			(layer "B.Fab")
			(effects
				(font
					(size 1.27 1.27)
				)
				(justify mirror)
			)
		)
		(duplicate_pad_numbers_are_jumpers no)
		(fp_line
			(start 0.299974 -0.150114)
			(end -0.299974 -0.150114)
			(stroke
				(width 0.1)
				(type default)
			)
			(layer "B.Fab")
		)
		(fp_line
			(start -0.299974 -0.150114)
			(end -0.299974 0.150114)
			(stroke
				(width 0.1)
				(type default)
			)
			(layer "B.Fab")
		)
		(fp_line
			(start 0.299974 0.150114)
			(end 0.299974 -0.150114)
			(stroke
				(width 0.1)
				(type default)
			)
			(layer "B.Fab")
		)
		(fp_line
			(start -0.299974 0.150114)
			(end 0.299974 0.150114)
			(stroke
				(width 0.1)
				(type default)
			)
			(layer "B.Fab")
		)
		(pad "1" smd rect
			(at 0.2667 0 270)
			(size 0.3048 0.381)
			(layers "B.Cu" "B.Mask" "B.Paste")
			(net "P1V25_PEX2")
		)
		(pad "2" smd rect
			(at -0.2667 0 270)
			(size 0.3048 0.381)
			(layers "B.Cu" "B.Mask" "B.Paste")
			(net "GND")
		)
	)
	(footprint ""
		(layer "B.Cu")
		(at 209.587084 -246.671592 90)
		(property "Reference" "R6341"
			(at 0 0 90)
			(layer "B.SilkS")
			(hide yes)
			(effects
				(font
					(size 1.27 1.27)
				)
				(justify mirror)
			)
		)
		(property "Value" ""
			(at 0 0 90)
			(layer "B.Fab")
			(effects
				(font
					(size 1.27 1.27)
				)
				(justify mirror)
			)
		)
		(duplicate_pad_numbers_are_jumpers no)
		(fp_line
			(start 0.7874 -0.4064)
			(end -0.7874 -0.4064)
			(stroke
				(width 0.1524)
				(type default)
			)
			(layer "B.SilkS")
		)
		(fp_line
			(start -0.7874 -0.4064)
			(end -0.7874 0.4064)
			(stroke
				(width 0.1524)
				(type default)
			)
			(layer "B.SilkS")
		)
		(fp_line
			(start 0.7874 0.4064)
			(end 0.7874 -0.4064)
			(stroke
				(width 0.1524)
				(type default)
			)
			(layer "B.SilkS")
		)
		(fp_line
			(start -0.7874 0.4064)
			(end 0.7874 0.4064)
			(stroke
				(width 0.1524)
				(type default)
			)
			(layer "B.SilkS")
		)
		(fp_line
			(start 0.67945 -0.305054)
			(end 0.12065 -0.305054)
			(stroke
				(width 0.1)
				(type default)
			)
			(layer "B.Fab")
		)
		(fp_line
			(start 0.12065 -0.305054)
			(end 0.12065 -0.2794)
			(stroke
				(width 0.1)
				(type default)
			)
			(layer "B.Fab")
		)
		(fp_line
			(start -0.12065 -0.3048)
			(end -0.67945 -0.3048)
			(stroke
				(width 0.1)
				(type default)
			)
			(layer "B.Fab")
		)
		(fp_line
			(start -0.67945 -0.3048)
			(end -0.67945 0.3048)
			(stroke
				(width 0.1)
				(type default)
			)
			(layer "B.Fab")
		)
		(fp_line
			(start 0.12065 -0.2794)
			(end -0.12065 -0.2794)
			(stroke
				(width 0.1)
				(type default)
			)
			(layer "B.Fab")
		)
		(fp_line
			(start -0.12065 -0.2794)
			(end -0.12065 -0.3048)
			(stroke
				(width 0.1)
				(type default)
			)
			(layer "B.Fab")
		)
		(fp_line
			(start 0.12065 0.2794)
			(end 0.12065 0.3048)
			(stroke
				(width 0.1)
				(type default)
			)
			(layer "B.Fab")
		)
		(fp_line
			(start -0.120396 0.2794)
			(end 0.12065 0.2794)
			(stroke
				(width 0.1)
				(type default)
			)
			(layer "B.Fab")
		)
		(fp_line
			(start 0.67945 0.3048)
			(end 0.67945 -0.305054)
			(stroke
				(width 0.1)
				(type default)
			)
			(layer "B.Fab")
		)
		(fp_line
			(start 0.12065 0.3048)
			(end 0.67945 0.3048)
			(stroke
				(width 0.1)
				(type default)
			)
			(layer "B.Fab")
		)
		(fp_line
			(start -0.120396 0.3048)
			(end -0.120396 0.2794)
			(stroke
				(width 0.1)
				(type default)
			)
			(layer "B.Fab")
		)
		(fp_line
			(start -0.67945 0.3048)
			(end -0.120396 0.3048)
			(stroke
				(width 0.1)
				(type default)
			)
			(layer "B.Fab")
		)
		(pad "1" smd circle
			(at 0.40005 0 270)
			(size 0 0)
			(layers "B.Cu" "B.Mask" "B.Paste")
			(net "PEX_MUX_A2")
		)
		(pad "2" smd circle
			(at -0.40005 0 270)
			(size 0 0)
			(layers "B.Cu" "B.Mask" "B.Paste")
			(net "GND")
		)
	)
	(footprint ""
		(layer "B.Cu")
		(at 66.774822 -297.79976 -90)
		(property "Reference" "C1174"
			(at 0 0 90)
			(layer "B.SilkS")
			(hide yes)
			(effects
				(font
					(size 1.27 1.27)
				)
				(justify mirror)
			)
		)
		(property "Value" ""
			(at 0 0 90)
			(layer "B.Fab")
			(effects
				(font
					(size 1.27 1.27)
				)
				(justify mirror)
			)
		)
		(duplicate_pad_numbers_are_jumpers no)
		(fp_line
			(start -0.299974 0.150114)
			(end 0.299974 0.150114)
			(stroke
				(width 0.1)
				(type default)
			)
			(layer "B.Fab")
		)
		(fp_line
			(start 0.299974 0.150114)
			(end 0.299974 -0.150114)
			(stroke
				(width 0.1)
				(type default)
			)
			(layer "B.Fab")
		)
		(fp_line
			(start -0.299974 -0.150114)
			(end -0.299974 0.150114)
			(stroke
				(width 0.1)
				(type default)
			)
			(layer "B.Fab")
		)
		(fp_line
			(start 0.299974 -0.150114)
			(end -0.299974 -0.150114)
			(stroke
				(width 0.1)
				(type default)
			)
			(layer "B.Fab")
		)
		(pad "1" smd rect
			(at 0.2667 0 90)
			(size 0.3048 0.381)
			(layers "B.Cu" "B.Mask" "B.Paste")
			(net "P0V8_SERDES_VDDA_PEX0")
		)
		(pad "2" smd rect
			(at -0.2667 0 90)
			(size 0.3048 0.381)
			(layers "B.Cu" "B.Mask" "B.Paste")
			(net "GND")
		)
	)
	(footprint ""
		(layer "B.Cu")
		(at 329.807316 -231.515412)
		(property "Reference" "R2621"
			(at 0 0 0)
			(layer "B.SilkS")
			(hide yes)
			(effects
				(font
					(size 1.27 1.27)
				)
				(justify mirror)
			)
		)
		(property "Value" ""
			(at 0 0 0)
			(layer "B.Fab")
			(effects
				(font
					(size 1.27 1.27)
				)
				(justify mirror)
			)
		)
		(duplicate_pad_numbers_are_jumpers no)
		(fp_line
			(start -0.7874 -0.4064)
			(end -0.7874 0.4064)
			(stroke
				(width 0.1524)
				(type default)
			)
			(layer "B.SilkS")
		)
		(fp_line
			(start -0.7874 0.4064)
			(end 0.7874 0.4064)
			(stroke
				(width 0.1524)
				(type default)
			)
			(layer "B.SilkS")
		)
		(fp_line
			(start 0.7874 -0.4064)
			(end -0.7874 -0.4064)
			(stroke
				(width 0.1524)
				(type default)
			)
			(layer "B.SilkS")
		)
		(fp_line
			(start 0.7874 0.4064)
			(end 0.7874 -0.4064)
			(stroke
				(width 0.1524)
				(type default)
			)
			(layer "B.SilkS")
		)
		(fp_line
			(start -0.67945 -0.3048)
			(end -0.67945 0.3048)
			(stroke
				(width 0.1)
				(type default)
			)
			(layer "B.Fab")
		)
		(fp_line
			(start -0.67945 0.3048)
			(end -0.120396 0.3048)
			(stroke
				(width 0.1)
				(type default)
			)
			(layer "B.Fab")
		)
		(fp_line
			(start -0.12065 -0.3048)
			(end -0.67945 -0.3048)
			(stroke
				(width 0.1)
				(type default)
			)
			(layer "B.Fab")
		)
		(fp_line
			(start -0.12065 -0.2794)
			(end -0.12065 -0.3048)
			(stroke
				(width 0.1)
				(type default)
			)
			(layer "B.Fab")
		)
		(fp_line
			(start -0.120396 0.2794)
			(end 0.12065 0.2794)
			(stroke
				(width 0.1)
				(type default)
			)
			(layer "B.Fab")
		)
		(fp_line
			(start -0.120396 0.3048)
			(end -0.120396 0.2794)
			(stroke
				(width 0.1)
				(type default)
			)
			(layer "B.Fab")
		)
		(fp_line
			(start 0.12065 -0.305054)
			(end 0.12065 -0.2794)
			(stroke
				(width 0.1)
				(type default)
			)
			(layer "B.Fab")
		)
		(fp_line
			(start 0.12065 -0.2794)
			(end -0.12065 -0.2794)
			(stroke
				(width 0.1)
				(type default)
			)
			(layer "B.Fab")
		)
		(fp_line
			(start 0.12065 0.2794)
			(end 0.12065 0.3048)
			(stroke
				(width 0.1)
				(type default)
			)
			(layer "B.Fab")
		)
		(fp_line
			(start 0.12065 0.3048)
			(end 0.67945 0.3048)
			(stroke
				(width 0.1)
				(type default)
			)
			(layer "B.Fab")
		)
		(fp_line
			(start 0.67945 -0.305054)
			(end 0.12065 -0.305054)
			(stroke
				(width 0.1)
				(type default)
			)
			(layer "B.Fab")
		)
		(fp_line
			(start 0.67945 0.3048)
			(end 0.67945 -0.305054)
			(stroke
				(width 0.1)
				(type default)
			)
			(layer "B.Fab")
		)
		(pad "1" smd circle
			(at 0.40005 0 180)
			(size 0 0)
			(layers "B.Cu" "B.Mask" "B.Paste")
			(net "JTAG_FPGA_TDI")
		)
		(pad "2" smd circle
			(at -0.40005 0 180)
			(size 0 0)
			(layers "B.Cu" "B.Mask" "B.Paste")
			(net "P3V3_AUX")
		)
	)
	(footprint ""
		(layer "B.Cu")
		(at 106.00055 -308.580028 90)
		(property "Reference" "C4191"
			(at 0 0 90)
			(layer "B.SilkS")
			(hide yes)
			(effects
				(font
					(size 1.27 1.27)
				)
				(justify mirror)
			)
		)
		(property "Value" ""
			(at 0 0 90)
			(layer "B.Fab")
			(effects
				(font
					(size 1.27 1.27)
				)
				(justify mirror)
			)
		)
		(duplicate_pad_numbers_are_jumpers no)
		(fp_line
			(start 1.2954 -0.5842)
			(end -1.2954 -0.5842)
			(stroke
				(width 0.1524)
				(type default)
			)
			(layer "B.SilkS")
		)
		(fp_line
			(start -1.2954 -0.5842)
			(end -1.2954 0.5842)
			(stroke
				(width 0.1524)
				(type default)
			)
			(layer "B.SilkS")
		)
		(fp_line
			(start 1.2954 0.5842)
			(end 1.2954 -0.5842)
			(stroke
				(width 0.1524)
				(type default)
			)
			(layer "B.SilkS")
		)
		(fp_line
			(start -1.2954 0.5842)
			(end 1.2954 0.5842)
			(stroke
				(width 0.1524)
				(type default)
			)
			(layer "B.SilkS")
		)
		(fp_line
			(start 0.8636 -0.4572)
			(end -0.8636 -0.4572)
			(stroke
				(width 0.1)
				(type default)
			)
			(layer "B.Fab")
		)
		(fp_line
			(start -0.8636 -0.4572)
			(end -0.8636 -0.4064)
			(stroke
				(width 0.1)
				(type default)
			)
			(layer "B.Fab")
		)
		(fp_line
			(start 1.1938 -0.4064)
			(end 0.8636 -0.4064)
			(stroke
				(width 0.1)
				(type default)
			)
			(layer "B.Fab")
		)
		(fp_line
			(start 0.8636 -0.4064)
			(end 0.8636 -0.4572)
			(stroke
				(width 0.1)
				(type default)
			)
			(layer "B.Fab")
		)
		(fp_line
			(start -0.8636 -0.4064)
			(end -1.1938 -0.4064)
			(stroke
				(width 0.1)
				(type default)
			)
			(layer "B.Fab")
		)
		(fp_line
			(start -1.1938 -0.4064)
			(end -1.1938 0.4064)
			(stroke
				(width 0.1)
				(type default)
			)
			(layer "B.Fab")
		)
		(fp_line
			(start 1.1938 0.4064)
			(end 1.1938 -0.4064)
			(stroke
				(width 0.1)
				(type default)
			)
			(layer "B.Fab")
		)
		(fp_line
			(start 0.8636 0.4064)
			(end 1.1938 0.4064)
			(stroke
				(width 0.1)
				(type default)
			)
			(layer "B.Fab")
		)
		(fp_line
			(start -0.8636 0.4064)
			(end -0.8636 0.4572)
			(stroke
				(width 0.1)
				(type default)
			)
			(layer "B.Fab")
		)
		(fp_line
			(start -1.1938 0.4064)
			(end -0.8636 0.4064)
			(stroke
				(width 0.1)
				(type default)
			)
			(layer "B.Fab")
		)
		(fp_line
			(start 0.8636 0.4572)
			(end 0.8636 0.4064)
			(stroke
				(width 0.1)
				(type default)
			)
			(layer "B.Fab")
		)
		(fp_line
			(start -0.8636 0.4572)
			(end 0.8636 0.4572)
			(stroke
				(width 0.1)
				(type default)
			)
			(layer "B.Fab")
		)
		(pad "1" smd rect
			(at 0.7366 0)
			(size 0.7112 0.8128)
			(layers "B.Cu" "B.Mask" "B.Paste")
			(net "P0V8_PEX0")
		)
		(pad "2" smd rect
			(at -0.7366 0)
			(size 0.7112 0.8128)
			(layers "B.Cu" "B.Mask" "B.Paste")
			(net "GND")
		)
	)
)
